# BASEBOARD_FAB2 (Tioga Pass) — schematic netlist excerpt (pin names and nets, part order shuffled) for the footprints in the layout excerpt that follows; sources: Cadence DE-HDL packaged netlist, KiCad conversion of Wiwynn_Tioga_Pass_MB.brd

F25W1  POLYSW-D5A6V-2-GP-U  pkg DISCRET-GA1  page 252 : \1\ = P5V_VGA ; \2\ = P5V_VGA_D
C8U12  CAP  100UF 4V 20% X5R  pkg 0805  page 225 : A = PVDDQ_GHJ ; B = GND
R3L8  RES  0.0 5% CHIP  pkg 0402  page 219 : A = VR_PVDDQ_DEF_PH2_VCIN ; B = P5V_STBY

(kicad_pcb
	(version 20260206)
	(generator "pcbnew")
	(generator_version "10.0")
	(general
		(thickness 1.6)
		(legacy_teardrops no)
	)
	(paper "A4")
	(title_block
		(title "Wiwynn_Tioga_Pass_MB.brd")
		(comment 1 "Tioga Pass / footprints 3357-3359 of 4770")
	)
	(layers
		(0 "F.Cu" signal "TOP")
		(4 "In1.Cu" signal "L2GND")
		(6 "In2.Cu" signal "L3")
		(8 "In3.Cu" signal "L4GND")
		(10 "In4.Cu" signal "L5")
		(12 "In5.Cu" signal "L6GND")
		(14 "In6.Cu" signal "L7VCC")
		(16 "In7.Cu" signal "L8VCC")
		(18 "In8.Cu" signal "L9GND")
		(20 "In9.Cu" signal "L10")
		(22 "In10.Cu" signal "L11GND")
		(24 "In11.Cu" signal "L12")
		(26 "In12.Cu" signal "L13GND")
		(2 "B.Cu" signal "BOTTOM")
		(9 "F.Adhes" user "F.Adhesive")
		(11 "B.Adhes" user "B.Adhesive")
		(13 "F.Paste" user "Package Geometry/Pastemask Top")
		(15 "B.Paste" user "Package Geometry/Pastemask Bottom")
		(5 "F.SilkS" user "Ref Des/Silkscreen Top")
		(7 "B.SilkS" user "Ref Des/Silkscreen Bottom")
		(1 "F.Mask" user "Board Geometry/Soldermask Top")
		(3 "B.Mask" user "Board Geometry/Soldermask Bottom")
		(17 "Dwgs.User" user "User.Drawings")
		(19 "Cmts.User" user "User.Comments")
		(21 "Eco1.User" user "User.Eco1")
		(23 "Eco2.User" user "User.Eco2")
		(25 "Edge.Cuts" user "Board Geometry/Outline")
		(27 "Margin" user)
		(31 "F.CrtYd" user "Package Geometry/Place Bound Top")
		(29 "B.CrtYd" user "Package Geometry/Place Bound Bottom")
		(35 "F.Fab" user "Ref Des/Assembly Top")
		(33 "B.Fab" user "Ref Des/Assembly Bottom")
	)
	(footprint ""
		(layer "B.Cu")
		(at 349.2246 -147.715224 -90)
		(property "Reference" "R3L8"
			(at 0 0 90)
			(layer "B.SilkS")
			(hide yes)
			(effects
				(font
					(size 1.27 1.27)
				)
				(justify mirror)
			)
		)
		(property "Value" ""
			(at 0 0 90)
			(layer "B.Fab")
			(effects
				(font
					(size 1.27 1.27)
				)
				(justify mirror)
			)
		)
		(duplicate_pad_numbers_are_jumpers no)
		(fp_poly
			(pts
				(xy 0.2794 -0.1016) (xy -0.2794 -0.1016) (xy -0.2794 0.9906) (xy 0.2794 0.9906)
			)
			(stroke
				(width 0)
				(type default)
			)
			(fill no)
			(layer "B.CrtYd")
		)
		(fp_line
			(start -0.2794 0.9906)
			(end -0.2794 -0.1016)
			(stroke
				(width 0.1)
				(type default)
			)
			(layer "B.Fab")
		)
		(fp_line
			(start 0.2794 0.9906)
			(end -0.2794 0.9906)
			(stroke
				(width 0.1)
				(type default)
			)
			(layer "B.Fab")
		)
		(fp_line
			(start -0.2794 -0.1016)
			(end 0.2794 -0.1016)
			(stroke
				(width 0.1)
				(type default)
			)
			(layer "B.Fab")
		)
		(fp_line
			(start 0.2794 -0.1016)
			(end 0.2794 0.9906)
			(stroke
				(width 0.1)
				(type default)
			)
			(layer "B.Fab")
		)
		(pad "1" smd rect
			(at 0 0 90)
			(size 0.508 0.508)
			(layers "B.Cu" "B.Mask" "B.Paste")
			(net "VR_PVDDQ_DEF_PH2_VCIN")
		)
		(pad "2" smd rect
			(at 0 0.889 90)
			(size 0.508 0.508)
			(layers "B.Cu" "B.Mask" "B.Paste")
			(net "P5V_STBY")
		)
		(zone
			(layer "B.Cu")
			(hatch none 0.5)
			(connect_pads
				(clearance 0)
			)
			(min_thickness 0.25)
			(keepout
				(tracks not_allowed)
				(vias allowed)
				(pads allowed)
				(copperpour not_allowed)
				(footprints allowed)
			)
			(placement
				(enabled no)
				(sheetname "")
			)
			(fill
				(thermal_gap 0.5)
				(thermal_bridge_width 0.5)
				(island_removal_mode 0)
			)
			(polygon
				(pts
					(xy 348.5896 -147.461224) (xy 348.5896 -147.969224) (xy 348.9706 -147.969224) (xy 348.9706 -147.461224)
				)
			)
		)
		(zone
			(layer "B.Cu")
			(hatch none 0.5)
			(connect_pads
				(clearance 0)
			)
			(min_thickness 0.25)
			(keepout
				(tracks allowed)
				(vias not_allowed)
				(pads allowed)
				(copperpour not_allowed)
				(footprints allowed)
			)
			(placement
				(enabled no)
				(sheetname "")
			)
			(fill
				(thermal_gap 0.5)
				(thermal_bridge_width 0.5)
				(island_removal_mode 0)
			)
			(polygon
				(pts
					(xy 348.9706 -147.461224) (xy 348.9706 -147.969224) (xy 348.5896 -147.969224) (xy 348.5896 -147.461224)
				)
			)
		)
	)
	(footprint ""
		(layer "B.Cu")
		(at 487.357674 -52.946046 -90)
		(property "Reference" "F25W1"
			(at 0 0 90)
			(layer "B.SilkS")
			(hide yes)
			(effects
				(font
					(size 1.27 1.27)
				)
				(justify mirror)
			)
		)
		(property "Value" "*"
			(at 0 -5.312918 270)
			(unlocked yes)
			(layer "B.Fab")
			(hide yes)
			(effects
				(font
					(size 1.27 1.016)
					(thickness 0.1524)
				)
				(justify mirror)
			)
		)
		(property "Device Type" "POLYSW-D5A6V-2-GP-U_DISCRET-GAA"
			(at 0 -7.344918 270)
			(unlocked yes)
			(layer "B.Fab")
			(hide yes)
			(effects
				(font
					(size 1.27 1.016)
					(thickness 0.1524)
				)
				(justify mirror)
			)
		)
		(duplicate_pad_numbers_are_jumpers no)
		(fp_line
			(start -1.0287 1.6637)
			(end -1.0287 -1.6637)
			(stroke
				(width 0.1524)
				(type default)
			)
			(layer "B.SilkS")
		)
		(fp_line
			(start 1.0287 1.6637)
			(end -1.0287 1.6637)
			(stroke
				(width 0.1524)
				(type default)
			)
			(layer "B.SilkS")
		)
		(fp_line
			(start -1.0287 -1.6637)
			(end 1.0287 -1.6637)
			(stroke
				(width 0.1524)
				(type default)
			)
			(layer "B.SilkS")
		)
		(fp_line
			(start 1.0287 -1.6637)
			(end 1.0287 1.6637)
			(stroke
				(width 0.1524)
				(type default)
			)
			(layer "B.SilkS")
		)
		(fp_rect
			(start 1.1049 1.7399)
			(end -1.1049 -1.7399)
			(stroke
				(width 0)
				(type default)
			)
			(fill no)
			(layer "B.CrtYd")
		)
		(fp_poly
			(pts
				(xy 1.1049 -1.7399) (xy -1.1049 -1.7399) (xy -1.1049 1.7399) (xy 1.1049 1.7399)
			)
			(stroke
				(width 0)
				(type default)
			)
			(fill no)
			(layer "B.Fab")
		)
		(pad "1" smd rect
			(at 0 -0.9398 90)
			(size 1.6002 0.9652)
			(layers "B.Cu" "B.Mask" "B.Paste")
			(net "P5V_VGA")
		)
		(pad "2" smd rect
			(at 0 0.9398 90)
			(size 1.6002 0.9652)
			(layers "B.Cu" "B.Mask" "B.Paste")
			(net "P5V_VGA_D")
		)
	)
	(footprint ""
		(layer "B.Cu")
		(at 102.080568 3.81 90)
		(property "Reference" "C8U12"
			(at 0 0 90)
			(layer "B.SilkS")
			(hide yes)
			(effects
				(font
					(size 1.27 1.27)
				)
				(justify mirror)
			)
		)
		(property "Value" ""
			(at 0 0 90)
			(layer "B.Fab")
			(effects
				(font
					(size 1.27 1.27)
				)
				(justify mirror)
			)
		)
		(duplicate_pad_numbers_are_jumpers no)
		(fp_poly
			(pts
				(xy 0.7239 -0.2159) (xy -0.7239 -0.2159) (xy -0.7239 1.9939) (xy 0.7239 1.9939)
			)
			(stroke
				(width 0)
				(type default)
			)
			(fill no)
			(layer "B.CrtYd")
		)
		(fp_line
			(start 0.7239 -0.2159)
			(end 0.7239 1.9939)
			(stroke
				(width 0.1)
				(type default)
			)
			(layer "B.Fab")
		)
		(fp_line
			(start -0.7239 -0.2159)
			(end 0.7239 -0.2159)
			(stroke
				(width 0.1)
				(type default)
			)
			(layer "B.Fab")
		)
		(fp_line
			(start 0.7239 1.9939)
			(end -0.7239 1.9939)
			(stroke
				(width 0.1)
				(type default)
			)
			(layer "B.Fab")
		)
		(fp_line
			(start -0.7239 1.9939)
			(end -0.7239 -0.2159)
			(stroke
				(width 0.1)
				(type default)
			)
			(layer "B.Fab")
		)
		(pad "1" smd rect
			(at 0 0 270)
			(size 1.27 1.016)
			(layers "B.Cu" "B.Mask" "B.Paste")
			(net "PVDDQ_GHJ")
		)
		(pad "2" smd rect
			(at 0 1.778 270)
			(size 1.27 1.016)
			(layers "B.Cu" "B.Mask" "B.Paste")
			(net "GND")
		)
		(zone
			(layer "B.Cu")
			(hatch none 0.5)
			(connect_pads
				(clearance 0)
			)
			(min_thickness 0.25)
			(keepout
				(tracks not_allowed)
				(vias allowed)
				(pads allowed)
				(copperpour not_allowed)
				(footprints allowed)
			)
			(placement
				(enabled no)
				(sheetname "")
			)
			(fill
				(thermal_gap 0.5)
				(thermal_bridge_width 0.5)
				(island_removal_mode 0)
			)
			(polygon
				(pts
					(xy 102.588568 3.175) (xy 102.588568 4.445) (xy 103.350568 4.445) (xy 103.350568 3.175)
				)
			)
		)
	)
)
